FILE_TYPE = CONNECTIVITY;
{Allegro Design Entry HDL 17.2-2016 S081 (4005846) 1/11/2022}
"PAGE_NUMBER" = 165;
0"NC";
1"GND\g";
2"GND\g";
3"GND\g";
4"GND\g";
5"GND\g";
6"GND\g";
7"GND\g";
8"P12V_AUX\g";
9"GND\g";
10"GND\g";
11"GND\g";
12"P3V3_AUX\g";
13"P12V_AUX\g";
14"P3V3_AUX\g";
15"GND\g";
16"PWRGD_P3V3_AUX";
17"SW_P3V3_AUX_BOOT";
18"SW_P3V3_AUX_BOOTR";
19"P3V3_AUX_VOS";
20"NC_PU9_4";
21"NC_PU9_3";
22"NC_PU9_1";
23"NC_PU9_2";
24"P3V3_AUX_ILIM";
25"P3V3_AUX_SS";
26"P3V3_AUX_MODE";
27"NC_HICCUP";
28"P3V3_AUX_EN";
29"MB0_P12V_STBY_PWRGD";
30"P3V3_AUX_VCC";
31"P3V3_AUX_VDRV";
32"SW_P3V3_AUX_FLT";
33"P3V3_AUX_FB";
34"SW_P3V3_AUX_BOOT_R";
35"GND\g";
36"GND\g";
37"P12V_AUX\g";
38"GND\g";
39"GND\g";
40"SW_P3V3_AUX_SW";
41"P3V3_AUX\g";
%"GND"
"1","(-3275,-1650)","0","pure_quanta_power","I1";
;
HDL_POWER"GND"
SIZE"1B"
CDS_LIB"pure_quanta_power";
"A<SIZE-1..0>\NAC"1;
%"GND"
"1","(-2125,-1325)","0","pure_quanta_power","I10";
;
HDL_POWER"GND"
CDS_LIB"pure_quanta_power"
SIZE"1B";
"A<SIZE-1..0>\NAC"2;
%"Q_RES"
"2","(-2125,-1150)","0","pure_quanta","I11";
;
LOCATION"PR832"
$SEC"1"
CDS_SEC"1"
MATERIAL"CHIP"
WATTAGE"1/16W"
TOLERANCE"5%"
PACK_TYPE"0402LF"
PART_NUMBER"CS00002JB13"
VALUE"0"
CDS_LIB"pure_quanta";
"A"
$PN"1"26;
"B"
$PN"2"2;
%"GND"
"1","(-1725,-1450)","0","pure_quanta_power","I12";
;
HDL_POWER"GND"
SIZE"1B"
CDS_LIB"pure_quanta_power";
"A<SIZE-1..0>\NAC"3;
%"Q_RES"
"2","(-1725,-1250)","0","pure_quanta","I13";
;
LOCATION"PR833"
$SEC"1"
CDS_SEC"1"
VALUE"1.5K"
PACK_TYPE"0402LF"
MATERIAL"EMPTY"
TOLERANCE"1%"
WATTAGE"1/16W"
PART_NUMBER"CS21502FB07"
CDS_LIB"pure_quanta";
"A"
$PN"1"25;
"B"
$PN"2"3;
%"GND"
"1","(-1325,-1550)","0","pure_quanta_power","I14";
;
HDL_POWER"GND"
CDS_LIB"pure_quanta_power"
SIZE"1B";
"A<SIZE-1..0>\NAC"4;
%"Q_RES"
"2","(-1325,-1350)","0","pure_quanta","I15";
;
LOCATION"PR834"
$SEC"1"
CDS_SEC"1"
VALUE"21.5K"
MATERIAL"CHIP"
PART_NUMBER"CS32152FB04"
PACK_TYPE"0402LF"
TOLERANCE"1%"
WATTAGE"1/16W"
CDS_LIB"pure_quanta";
"A"
$PN"1"24;
"B"
$PN"2"4;
%"GND"
"1","(-2025,-775)","0","pure_quanta_power","I16";
;
HDL_POWER"GND"
CDS_LIB"pure_quanta_power"
SIZE"1B";
"A<SIZE-1..0>\NAC"5;
%"Q_CAP"
"1","(-2025,-550)","0","pure_quanta","I17";
;
LOCATION"PC581"
$SEC"1"
CDS_SEC"1"
MATERIAL"X6S"
VALUE"4.7UF"
TOLERANCE"10%"
PART_NUMBER"CH5473KE902"
VOLTAGE"16V"
PACK_TYPE"C0603"
CDS_LIB"pure_quanta";
"B"
$PN"2"5;
"A"
$PN"1"31;
%"Q_RES"
"1","(-1775,-325)","0","pure_quanta","I18";
;
LOCATION"PR837"
$SEC"1"
CDS_SEC"1"
PACK_TYPE"0402LF"
VALUE"1"
TOLERANCE"1%"
WATTAGE"1/16W"
MATERIAL"CHIP"
CDS_LIB"pure_quanta"
PART_NUMBER"CS-1002FB04";
"B"
$PN"2"30;
"A"
$PN"1"31;
%"GND"
"1","(-1600,-775)","0","pure_quanta_power","I19";
;
HDL_POWER"GND"
SIZE"1B"
CDS_LIB"pure_quanta_power";
"A<SIZE-1..0>\NAC"6;
%"Q_RES"
"2","(-3275,-1350)","0","pure_quanta","I2";
;
$LOCATION"R3118"
CDS_LOCATION"R3118"
$SEC"1"
CDS_SEC"1"
PACK_TYPE"0402LF"
PART_NUMBER"CS38662FB05"
VALUE"86.6K"
TOLERANCE"1%"
WATTAGE"1/16W"
MATERIAL"EMPTY"
CDS_LIB"pure_quanta";
"A"
$PN"1"28;
"B"
$PN"2"1;
%"Q_CAP"
"1","(-1600,-550)","0","pure_quanta","I20";
;
LOCATION"PC591"
$SEC"1"
CDS_SEC"1"
TOLERANCE"10%"
MATERIAL"X6S"
VOLTAGE"16V"
VALUE"2.2UF"
PACK_TYPE"C0603"
PART_NUMBER"CH5223KE901"
CDS_LIB"pure_quanta";
"B"
$PN"2"6;
"A"
$PN"1"30;
%"NCP3284AMNTXG"
"1","(-75,-675)","0","pure_quanta","I21";
;
LOCATION"PU9"
$SEC"1"
CDS_SEC"1"
PART_NUMBER"AL003284002"
VALUE"NCP3284AMNTXG"
MATERIAL"IC"
PART_TYPE"SMLF"
CDS_LMAN_SYM_OUTLINE"-300,700,250,-700"
NEEDS_NO_SIZE"TRUE"
CDS_LIB"pure_quanta";
"GL2"
$PN"37"20;
"SS"
$PN"29"25;
"GL1"
$PN"6"21;
"VDRV"
$PN"5"31;
"EN"
$PN"27"28;
"AGND"
$PN"32"36;
"VOS"
$PN"28"19;
"PGOOD"
$PN"2"16;
"PVIN"
$PN"20_24"32;
"SW"
$PN"11_18"40;
"NC1"
$PN"33"22;
"PGND"
$PN"7_10-19"36;
"HICCUP# \B"
$PN"35"27;
"VSNS-"
$PN"31"10;
"VCC"
$PN"4"30;
"PHASE"
$PN"25"18;
"ILIM"
$PN"1"24;
"BOOT"
$PN"26"17;
"FB"
$PN"30"33;
"VIN"
$PN"3"37;
"MODE||FSET"
$PN"36"26;
"NC2"
$PN"34"23;
%"GND"
"1","(-4500,675)","0","pure_quanta_power","I22";
;
HDL_POWER"GND"
SIZE"1B"
CDS_LIB"pure_quanta_power";
"A<SIZE-1..0>\NAC"7;
%"Q_CAP"
"1","(-4500,925)","0","pure_quanta","I23";
;
LOCATION"PC1649"
$SEC"1"
CDS_SEC"1"
PART_NUMBER"CH4106K1B01"
VOLTAGE"50V"
VALUE"100NF"
TOLERANCE"10%"
MATERIAL"X7R"
PACK_TYPE"C0402"
CDS_LIB"pure_quanta";
"B"
$PN"2"7;
"A"
$PN"1"8;
%"UNIVERSAL_POWER"
"1","(-4500,1550)","0","pure_quanta_power","I24";
;
HDL_POWER"P12V_AUX"
CDS_LIB"pure_quanta_power";
"A"8;
%"Q_INDUCTOR"
"1","(-4275,1150)","0","pure_quanta","I25";
;
LOCATION"PL58"
$SEC"1"
CDS_SEC"1"
PART_NUMBER"CV+10G0MZ04"
VALUE"100NH/16A"
MATERIAL"IND"
PACK_TYPE"SMLF"
NEEDS_NO_SIZE"TRUE"
CDS_LIB"pure_quanta";
"1"
$PN"1"8;
"2"
$PN"2"32;
%"Q_CAP"
"1","(-4025,275)","0","pure_quanta","I26";
;
LOCATION"PC2260"
$SEC"1"
CDS_SEC"1"
VALUE"22UF"
VOLTAGE"16V"
PART_NUMBER"CH6223MEA01"
MATERIAL"X6S"
PACK_TYPE"C0805"
TOLERANCE"20%"
CDS_LIB"pure_quanta";
"B"
$PN"2"38;
"A"
$PN"1"32;
%"GND"
"1","(-3950,550)","0","pure_quanta_power","I27";
;
HDL_POWER"GND"
CDS_LIB"pure_quanta_power"
SIZE"1B";
"A<SIZE-1..0>\NAC"39;
%"Q_CAPP"
"1","(-3950,925)","0","pure_quanta","I28";
;
LOCATION"PC3"
$SEC"1"
CDS_SEC"1"
MATERIAL"OSCON"
PACK_TYPE"THLF"
VOLTAGE"16V"
VALUE"270UF"
TOLERANCE"20%"
PART_NUMBER"CC72703MD38"
CDS_LIB"pure_quanta"
LOCATION"PC3";
"A"
$PN"1"32;
"B"
$PN"2"39;
%"Q_CAP"
"1","(-3700,275)","0","pure_quanta","I29";
;
LOCATION"PC2261"
$SEC"1"
CDS_SEC"1"
VOLTAGE"16V"
MATERIAL"X6S"
VALUE"22UF"
PACK_TYPE"C0805"
PART_NUMBER"CH6223MEA01"
TOLERANCE"20%"
CDS_LIB"pure_quanta";
"B"
$PN"2"38;
"A"
$PN"1"32;
%"GND"
"1","(-4025,-75)","0","pure_quanta_power","I3";
;
HDL_POWER"GND"
CDS_LIB"pure_quanta_power"
SIZE"1B";
"A<SIZE-1..0>\NAC"38;
%"Q_CAP"
"1","(-3375,275)","0","pure_quanta","I30";
;
LOCATION"PC2262"
$SEC"1"
CDS_SEC"1"
VOLTAGE"16V"
PART_NUMBER"CH6223MEA01"
VALUE"22UF"
PACK_TYPE"C0805"
TOLERANCE"20%"
MATERIAL"X6S"
CDS_LIB"pure_quanta";
"B"
$PN"2"38;
"A"
$PN"1"32;
%"Q_CAPP"
"1","(-3650,925)","0","pure_quanta","I31";
;
LOCATION"PC566"
$SEC"1"
CDS_SEC"1"
VOLTAGE"16V"
MATERIAL"OSCON"
PART_NUMBER"CC72703MD38"
PACK_TYPE"THLF"
TOLERANCE"20%"
VALUE"270UF"
CDS_LIB"pure_quanta"
LOCATION"PC566";
"A"
$PN"1"32;
"B"
$PN"2"39;
%"Q_CAP"
"1","(-3325,925)","0","pure_quanta","I32";
;
LOCATION"PC700"
$SEC"1"
CDS_SEC"1"
PART_NUMBER"CH6223MEA01"
PACK_TYPE"C0805"
VOLTAGE"16V"
TOLERANCE"20%"
MATERIAL"X6S"
VALUE"22UF"
CDS_LIB"pure_quanta";
"B"
$PN"2"39;
"A"
$PN"1"32;
%"Q_CAP"
"1","(-3050,275)","0","pure_quanta","I33";
;
LOCATION"PC2263"
$SEC"1"
CDS_SEC"1"
MATERIAL"X6S"
PART_NUMBER"CH6223MEA01"
PACK_TYPE"C0805"
VALUE"22UF"
VOLTAGE"16V"
TOLERANCE"20%"
CDS_LIB"pure_quanta";
"B"
$PN"2"38;
"A"
$PN"1"32;
%"Q_CAP"
"1","(-2725,275)","0","pure_quanta","I34";
;
LOCATION"PC2342"
$SEC"1"
CDS_SEC"1"
PART_NUMBER"CH6223MEA01"
VALUE"22UF"
PACK_TYPE"C0805"
VOLTAGE"16V"
MATERIAL"X6S"
TOLERANCE"20%"
CDS_LIB"pure_quanta";
"B"
$PN"2"38;
"A"
$PN"1"32;
%"Q_CAP"
"1","(-3000,925)","0","pure_quanta","I35";
;
LOCATION"PC570"
$SEC"1"
CDS_SEC"1"
MATERIAL"X6S"
PART_NUMBER"CH6223MEA01"
TOLERANCE"20%"
PACK_TYPE"C0805"
VALUE"22UF"
VOLTAGE"16V"
CDS_LIB"pure_quanta";
"B"
$PN"2"39;
"A"
$PN"1"32;
%"Q_CAP"
"1","(-2400,275)","0","pure_quanta","I36";
;
LOCATION"PC2343"
$SEC"1"
CDS_SEC"1"
PACK_TYPE"C0805"
PART_NUMBER"CH6223MEA01"
TOLERANCE"20%"
VOLTAGE"16V"
VALUE"22UF"
MATERIAL"X6S"
CDS_LIB"pure_quanta";
"B"
$PN"2"38;
"A"
$PN"1"32;
%"Q_CAP"
"1","(-2675,925)","0","pure_quanta","I37";
;
LOCATION"PC571"
$SEC"1"
CDS_SEC"1"
MATERIAL"X6S"
VALUE"22UF"
VOLTAGE"16V"
PART_NUMBER"CH6223MEA01"
TOLERANCE"20%"
PACK_TYPE"C0805"
CDS_LIB"pure_quanta";
"B"
$PN"2"39;
"A"
$PN"1"32;
%"Q_CAP"
"1","(-2350,925)","0","pure_quanta","I38";
;
LOCATION"PC576"
$SEC"1"
CDS_SEC"1"
MATERIAL"X6S"
VALUE"22UF"
PACK_TYPE"C0805"
PART_NUMBER"CH6223MEA01"
VOLTAGE"16V"
TOLERANCE"20%"
CDS_LIB"pure_quanta";
"B"
$PN"2"39;
"A"
$PN"1"32;
%"Q_CAP"
"1","(-2075,275)","0","pure_quanta","I39";
;
LOCATION"PC2344"
$SEC"1"
CDS_SEC"1"
PACK_TYPE"C0805"
PART_NUMBER"CH6223MEA01"
MATERIAL"X6S"
TOLERANCE"20%"
VOLTAGE"16V"
VALUE"22UF"
CDS_LIB"pure_quanta";
"B"
$PN"2"38;
"A"
$PN"1"32;
%"Q_RES"
"2","(-3275,-775)","0","pure_quanta","I4";
;
$LOCATION"R3117"
CDS_LOCATION"R3117"
$SEC"1"
CDS_SEC"1"
TOLERANCE"5%"
PART_NUMBER"CS45102JB03"
MATERIAL"EMPTY"
WATTAGE"1/16W"
VALUE"510K"
PACK_TYPE"0402LF"
CDS_LIB"pure_quanta";
"A"
$PN"1"13;
"B"
$PN"2"28;
%"Q_CAP"
"1","(-2025,925)","0","pure_quanta","I40";
;
LOCATION"PC701"
$SEC"1"
CDS_SEC"1"
VALUE"22UF"
VOLTAGE"16V"
MATERIAL"X6S"
TOLERANCE"20%"
PART_NUMBER"CH6223MEA01"
PACK_TYPE"C0805"
CDS_LIB"pure_quanta";
"B"
$PN"2"39;
"A"
$PN"1"32;
%"Q_CAP"
"1","(-1700,925)","0","pure_quanta","I41";
;
LOCATION"PC577"
$SEC"1"
CDS_SEC"1"
TOLERANCE"10%"
VALUE"0.1UF"
MATERIAL"X7R"
VOLTAGE"25V"
PART_NUMBER"CH4104K1B00"
PACK_TYPE"0402"
CDS_LIB"pure_quanta";
"B"
$PN"2"39;
"A"
$PN"1"32;
%"GND"
"1","(-875,275)","0","pure_quanta_power","I42";
;
HDL_POWER"GND"
SIZE"1B"
CDS_LIB"pure_quanta_power";
"A<SIZE-1..0>\NAC"9;
%"Q_CAP"
"1","(-875,550)","0","pure_quanta","I43";
;
LOCATION"PC702"
$SEC"1"
CDS_SEC"1"
VOLTAGE"16V"
VALUE"1UF"
TOLERANCE"10%"
MATERIAL"X7R"
PART_NUMBER"TMP_QCH5103K1900"
PACK_TYPE"0603"
CDS_LIB"pure_quanta";
"B"
$PN"2"9;
"A"
$PN"1"37;
%"UNIVERSAL_POWER"
"1","(-1125,875)","0","pure_quanta_power","I44";
;
HDL_POWER"P12V_AUX"
CDS_LIB"pure_quanta_power";
"A"37;
%"GND"
"1","(375,-1425)","0","pure_quanta_power","I45";
;
HDL_POWER"GND"
CDS_LIB"pure_quanta_power"
SIZE"1B";
"A<SIZE-1..0>\NAC"36;
%"GND"
"1","(575,-1125)","1","pure_quanta_power","I46";
;
HDL_POWER"GND"
CDS_LIB"pure_quanta_power"
SIZE"1B";
"A<SIZE-1..0>\NAC"10;
%"Q_RES"
"1","(850,-1175)","0","pure_quanta","I47";
;
LOCATION"PR836"
$SEC"1"
CDS_SEC"1"
PACK_TYPE"0402LF"
TOLERANCE"1%"
MATERIAL"CHIP"
PART_NUMBER"CS21002FB06"
WATTAGE"1/16W"
VALUE"1K"
CDS_LIB"pure_quanta";
"B"
$PN"2"12;
"A"
$PN"1"19;
%"Q_CAP"
"2","(750,-475)","0","pure_quanta","I48";
;
LOCATION"PC568"
$SEC"1"
CDS_SEC"1"
TOLERANCE"10%"
VALUE"0.22UF"
MATERIAL"X7R"
VOLTAGE"25V"
CDS_LIB"pure_quanta"
PART_NUMBER"CH4224K1B01"
PACK_TYPE"C0402";
"A"
$PN"1"18;
"B"
$PN"2"34;
%"Q_RES"
"1","(825,-275)","0","pure_quanta","I49";
;
LOCATION"PR835"
$SEC"1"
CDS_SEC"1"
PACK_TYPE"0402LF"
MATERIAL"CHIP"
WATTAGE"1/16W"
TOLERANCE"5%"
VALUE"0"
PART_NUMBER"CS00002JB13"
CDS_LIB"pure_quanta";
"B"
$PN"2"34;
"A"
$PN"1"17;
%"GND"
"1","(1225,-1925)","0","pure_quanta_power","I50";
;
HDL_POWER"GND"
SIZE"1B"
CDS_LIB"pure_quanta_power";
"A<SIZE-1..0>\NAC"11;
%"Q_RES"
"2","(1225,-1650)","0","pure_quanta","I51";
;
LOCATION"PR830"
$SEC"1"
CDS_SEC"1"
PACK_TYPE"0402LF"
WATTAGE"1/16W"
TOLERANCE"0.1%"
VALUE"15K"
MATERIAL"CHIP"
PART_NUMBER"CS31502BB03"
CDS_LIB"pure_quanta";
"A"
$PN"1"33;
"B"
$PN"2"11;
%"UNIVERSAL_POWER"
"1","(1100,-1075)","0","pure_quanta_power","I52";
;
HDL_POWER"P3V3_AUX"
CDS_LIB"pure_quanta_power";
"A"12;
%"Q_INDUCTOR"
"1","(1450,-650)","0","pure_quanta","I53";
;
LOCATION"PL73"
$SEC"1"
CDS_SEC"1"
PART_NUMBER"CV-15^0MZ02"
MATERIAL"IND"
PACK_TYPE"SMLF"
VALUE"1.5UH/53A"
CDS_LIB"pure_quanta"
NEEDS_NO_SIZE"TRUE";
"1"
$PN"1"40;
"2"
$PN"2"41;
%"Q_CAPP"
"1","(1675,-900)","0","pure_quanta","I55";
;
LOCATION"PC1866"
$SEC"1"
CDS_SEC"1"
PART_NUMBER"CC75601MD16"
MATERIAL"OSCON"
VOLTAGE"6.3V"
VALUE"560UF"
TOLERANCE"20%"
PACK_TYPE"THLF"
CDS_LIB"pure_quanta";
"A"
$PN"1"41;
"B"
$PN"2"35;
%"Q_CAP"
"2","(2125,-1775)","0","pure_quanta","I56";
;
LOCATION"PC569"
$SEC"1"
CDS_SEC"1"
VALUE"10PF"
TOLERANCE"1%"
MATERIAL"NPO"
PART_NUMBER"TMP_QCH0106F0B00"
PACK_TYPE"0402"
VOLTAGE"50V"
CDS_LIB"pure_quanta";
"A"
$PN"1"33;
"B"
$PN"2"41;
%"Q_RES"
"1","(2125,-1475)","0","pure_quanta","I57";
;
LOCATION"PR831"
$SEC"1"
CDS_SEC"1"
PART_NUMBER"CS34702BB05"
WATTAGE"1/16W"
VALUE"47K"
TOLERANCE"0.1%"
MATERIAL"CHIP"
PACK_TYPE"0402LF"
CDS_LIB"pure_quanta";
"B"
$PN"2"41;
"A"
$PN"1"33;
%"Q_CAPP"
"1","(2125,-900)","0","pure_quanta","I58";
;
LOCATION"PC1867"
$SEC"1"
CDS_SEC"1"
PACK_TYPE"THLF"
TOLERANCE"20%"
VALUE"560UF"
VOLTAGE"6.3V"
MATERIAL"OSCON"
PART_NUMBER"CC75601MD16"
CDS_LIB"pure_quanta";
"A"
$PN"1"41;
"B"
$PN"2"35;
%"Q_CAP"
"1","(2575,-875)","0","pure_quanta","I59";
;
LOCATION"PC1868"
$SEC"1"
CDS_SEC"1"
PART_NUMBER"CH6222MEA01"
MATERIAL"X6S"
VOLTAGE"10V"
TOLERANCE"20%"
PACK_TYPE"C0805"
VALUE"22UF"
CDS_LIB"pure_quanta";
"B"
$PN"2"35;
"A"
$PN"1"41;
%"P1V0_AUX"
"1","(-3275,-450)","0","pure_quanta_power","I6";
;
ROOM"VR_DDR1_POWER_STAGE"
HDL_POWER"P12V_AUX"
CDS_LIB"pure_quanta_power";
"A"13;
%"GND"
"1","(3750,-1275)","0","pure_quanta_power","I60";
;
HDL_POWER"GND"
SIZE"1B"
CDS_LIB"pure_quanta_power";
"A<SIZE-1..0>\NAC"35;
%"Q_CAP"
"1","(2975,-900)","0","pure_quanta","I61";
;
LOCATION"PC1599"
$SEC"1"
CDS_SEC"1"
VOLTAGE"10V"
VALUE"22UF"
TOLERANCE"20%"
MATERIAL"X6S"
PART_NUMBER"CH6222MEA01"
PACK_TYPE"C0805"
CDS_LIB"pure_quanta";
"B"
$PN"2"35;
"A"
$PN"1"41;
%"Q_CAP"
"1","(3350,-900)","0","pure_quanta","I62";
;
LOCATION"PC1600"
$SEC"1"
CDS_SEC"1"
VOLTAGE"10V"
TOLERANCE"20%"
MATERIAL"X6S"
PART_NUMBER"CH6222MEA01"
PACK_TYPE"C0805"
VALUE"22UF"
CDS_LIB"pure_quanta";
"B"
$PN"2"35;
"A"
$PN"1"41;
%"Q_CAP"
"1","(3750,-900)","0","pure_quanta","I63";
;
LOCATION"PC1869"
$SEC"1"
CDS_SEC"1"
TOLERANCE"10%"
PART_NUMBER"CH4104K1B00"
PACK_TYPE"0402"
VALUE"0.1UF"
MATERIAL"X7R"
VOLTAGE"25V"
CDS_LIB"pure_quanta";
"B"
$PN"2"35;
"A"
$PN"1"41;
%"UNIVERSAL_POWER"
"1","(4200,-375)","0","pure_quanta_power","I64";
;
HDL_POWER"P3V3_AUX"
CDS_LIB"pure_quanta_power";
"A"41;
%"Q_RES"
"2","(925,275)","0","pure_quanta","I65";
;
LOCATION"PR700"
$SEC"1"
CDS_SEC"1"
PART_NUMBER"CS31002FB08"
PACK_TYPE"0402LF"
MATERIAL"CHIP"
WATTAGE"1/16W"
VALUE"10K"
TOLERANCE"1%"
CDS_LIB"pure_quanta";
"A"
$PN"1"14;
"B"
$PN"2"16;
%"UNIVERSAL_POWER"
"1","(925,500)","0","pure_quanta_power","I66";
;
HDL_POWER"P3V3_AUX"
CDS_LIB"pure_quanta_power";
"A"14;
%"GND"
"1","(-2675,-1650)","0","pure_quanta_power","I7";
;
HDL_POWER"GND"
CDS_LIB"pure_quanta_power"
SIZE"1B";
"A<SIZE-1..0>\NAC"15;
%"Q_CAP"
"1","(-2675,-1350)","2","pure_quanta","I8";
;
LOCATION"PC1870"
$SEC"1"
CDS_SEC"1"
PART_NUMBER"CH4104K1B00"
TOLERANCE"10%"
MATERIAL"EMPTY"
VALUE"0.1UF"
PACK_TYPE"0402"
VOLTAGE"25V"
CDS_LIB"pure_quanta";
"B"
$PN"2"15;
"A"
$PN"1"28;
%"Q_RES"
"2","(-2775,-775)","0","pure_quanta","I9";
;
LOCATION"R1571"
$SEC"1"
CDS_SEC"1"
VALUE"0"
TOLERANCE"5%"
WATTAGE"1/16W"
MATERIAL"CHIP"
PART_NUMBER"CS00002JB13"
PACK_TYPE"0402LF"
CDS_LIB"pure_quanta"
LOCATION"R1571";
"A"
$PN"1"29;
"B"
$PN"2"28;
END.
